(kicad_pcb
	(version 20260206)
	(generator "pcbnew")
	(generator_version "10.0")
	(general
		(thickness 1.6)
		(legacy_teardrops no)
	)
	(paper "A4")
	(title_block
		(title "12092022_DA0F0TMDCD0_F0T_Management_Board_D_brd_V3_OCP.brd")
		(comment 1 "Grand Teton / footprints 851-856 of 1440")
	)
	(layers
		(0 "F.Cu" signal "TOP")
		(4 "In1.Cu" signal "GND")
		(6 "In2.Cu" signal "IN1")
		(8 "In3.Cu" signal "GND1")
		(10 "In4.Cu" signal "IN2")
		(12 "In5.Cu" signal "VCC")
		(14 "In6.Cu" signal "VCC1")
		(16 "In7.Cu" signal "IN3")
		(18 "In8.Cu" signal "GND2")
		(20 "In9.Cu" signal "IN4")
		(22 "In10.Cu" signal "GND3")
		(2 "B.Cu" signal "BOTTOM")
		(9 "F.Adhes" user "F.Adhesive")
		(11 "B.Adhes" user "B.Adhesive")
		(13 "F.Paste" user "Package Geometry/Pastemask Top")
		(15 "B.Paste" user "Package Geometry/Pastemask Bottom")
		(5 "F.SilkS" user "Ref Des/Silkscreen Top")
		(7 "B.SilkS" user "Ref Des/Silkscreen Bottom")
		(1 "F.Mask" user "Board Geometry/Soldermask Top")
		(3 "B.Mask" user "Board Geometry/Soldermask Bottom")
		(17 "Dwgs.User" user "User.Drawings")
		(19 "Cmts.User" user "User.Comments")
		(21 "Eco1.User" user "User.Eco1")
		(23 "Eco2.User" user "User.Eco2")
		(25 "Edge.Cuts" user "Board Geometry/Outline")
		(27 "Margin" user)
		(31 "F.CrtYd" user "Package Geometry/Place Bound Top")
		(29 "B.CrtYd" user "Package Geometry/Place Bound Bottom")
		(35 "F.Fab" user "Ref Des/Assembly Top")
		(33 "B.Fab" user "Ref Des/Assembly Bottom")
	)
	(footprint ""
		(layer "B.Cu")
		(at 64.262 -18.669 90)
		(property "Reference" "R629"
			(at 0 0 90)
			(layer "B.SilkS")
			(hide yes)
			(effects
				(font
					(size 1.27 1.27)
				)
				(justify mirror)
			)
		)
		(property "Value" ""
			(at 0 0 90)
			(layer "B.Fab")
			(effects
				(font
					(size 1.27 1.27)
				)
				(justify mirror)
			)
		)
		(duplicate_pad_numbers_are_jumpers no)
		(fp_line
			(start 0.7874 -0.4064)
			(end -0.7874 -0.4064)
			(stroke
				(width 0.1524)
				(type default)
			)
			(layer "B.SilkS")
		)
		(fp_line
			(start -0.7874 -0.4064)
			(end -0.7874 0.4064)
			(stroke
				(width 0.1524)
				(type default)
			)
			(layer "B.SilkS")
		)
		(fp_line
			(start 0.7874 0.4064)
			(end 0.7874 -0.4064)
			(stroke
				(width 0.1524)
				(type default)
			)
			(layer "B.SilkS")
		)
		(fp_line
			(start -0.7874 0.4064)
			(end 0.7874 0.4064)
			(stroke
				(width 0.1524)
				(type default)
			)
			(layer "B.SilkS")
		)
		(fp_line
			(start 0.67945 -0.305054)
			(end 0.12065 -0.305054)
			(stroke
				(width 0.1)
				(type default)
			)
			(layer "B.Fab")
		)
		(fp_line
			(start 0.12065 -0.305054)
			(end 0.12065 -0.2794)
			(stroke
				(width 0.1)
				(type default)
			)
			(layer "B.Fab")
		)
		(fp_line
			(start -0.12065 -0.3048)
			(end -0.67945 -0.3048)
			(stroke
				(width 0.1)
				(type default)
			)
			(layer "B.Fab")
		)
		(fp_line
			(start -0.67945 -0.3048)
			(end -0.67945 0.3048)
			(stroke
				(width 0.1)
				(type default)
			)
			(layer "B.Fab")
		)
		(fp_line
			(start 0.12065 -0.2794)
			(end -0.12065 -0.2794)
			(stroke
				(width 0.1)
				(type default)
			)
			(layer "B.Fab")
		)
		(fp_line
			(start -0.12065 -0.2794)
			(end -0.12065 -0.3048)
			(stroke
				(width 0.1)
				(type default)
			)
			(layer "B.Fab")
		)
		(fp_line
			(start 0.12065 0.2794)
			(end 0.12065 0.3048)
			(stroke
				(width 0.1)
				(type default)
			)
			(layer "B.Fab")
		)
		(fp_line
			(start -0.120396 0.2794)
			(end 0.12065 0.2794)
			(stroke
				(width 0.1)
				(type default)
			)
			(layer "B.Fab")
		)
		(fp_line
			(start 0.67945 0.3048)
			(end 0.67945 -0.305054)
			(stroke
				(width 0.1)
				(type default)
			)
			(layer "B.Fab")
		)
		(fp_line
			(start 0.12065 0.3048)
			(end 0.67945 0.3048)
			(stroke
				(width 0.1)
				(type default)
			)
			(layer "B.Fab")
		)
		(fp_line
			(start -0.120396 0.3048)
			(end -0.120396 0.2794)
			(stroke
				(width 0.1)
				(type default)
			)
			(layer "B.Fab")
		)
		(fp_line
			(start -0.67945 0.3048)
			(end -0.120396 0.3048)
			(stroke
				(width 0.1)
				(type default)
			)
			(layer "B.Fab")
		)
		(pad "1" smd circle
			(at 0.40005 0 270)
			(size 0 0)
			(layers "B.Cu" "B.Mask" "B.Paste")
			(net "BMC_CPLD_GPIO_2")
		)
		(pad "2" smd circle
			(at -0.40005 0 270)
			(size 0 0)
			(layers "B.Cu" "B.Mask" "B.Paste")
			(net "FM_DBG_SW_N")
		)
	)
	(footprint ""
		(layer "B.Cu")
		(at 56.983376 -53.376322)
		(property "Reference" "C81"
			(at 0 0 0)
			(layer "B.SilkS")
			(hide yes)
			(effects
				(font
					(size 1.27 1.27)
				)
				(justify mirror)
			)
		)
		(property "Value" ""
			(at 0 0 0)
			(layer "B.Fab")
			(effects
				(font
					(size 1.27 1.27)
				)
				(justify mirror)
			)
		)
		(duplicate_pad_numbers_are_jumpers no)
		(fp_line
			(start -0.7874 -0.4064)
			(end -0.7874 0.4064)
			(stroke
				(width 0.1524)
				(type default)
			)
			(layer "B.SilkS")
		)
		(fp_line
			(start -0.7874 0.4064)
			(end 0.7874 0.4064)
			(stroke
				(width 0.1524)
				(type default)
			)
			(layer "B.SilkS")
		)
		(fp_line
			(start 0.7874 -0.4064)
			(end -0.7874 -0.4064)
			(stroke
				(width 0.1524)
				(type default)
			)
			(layer "B.SilkS")
		)
		(fp_line
			(start 0.7874 0.4064)
			(end 0.7874 -0.4064)
			(stroke
				(width 0.1524)
				(type default)
			)
			(layer "B.SilkS")
		)
		(fp_line
			(start -0.67945 -0.3048)
			(end -0.67945 0.3048)
			(stroke
				(width 0.1)
				(type default)
			)
			(layer "B.Fab")
		)
		(fp_line
			(start -0.67945 0.3048)
			(end -0.120396 0.3048)
			(stroke
				(width 0.1)
				(type default)
			)
			(layer "B.Fab")
		)
		(fp_line
			(start -0.12065 -0.3048)
			(end -0.67945 -0.3048)
			(stroke
				(width 0.1)
				(type default)
			)
			(layer "B.Fab")
		)
		(fp_line
			(start -0.12065 -0.2794)
			(end -0.12065 -0.3048)
			(stroke
				(width 0.1)
				(type default)
			)
			(layer "B.Fab")
		)
		(fp_line
			(start -0.120396 0.2794)
			(end 0.12065 0.2794)
			(stroke
				(width 0.1)
				(type default)
			)
			(layer "B.Fab")
		)
		(fp_line
			(start -0.120396 0.3048)
			(end -0.120396 0.2794)
			(stroke
				(width 0.1)
				(type default)
			)
			(layer "B.Fab")
		)
		(fp_line
			(start 0.12065 -0.305054)
			(end 0.12065 -0.2794)
			(stroke
				(width 0.1)
				(type default)
			)
			(layer "B.Fab")
		)
		(fp_line
			(start 0.12065 -0.2794)
			(end -0.12065 -0.2794)
			(stroke
				(width 0.1)
				(type default)
			)
			(layer "B.Fab")
		)
		(fp_line
			(start 0.12065 0.2794)
			(end 0.12065 0.3048)
			(stroke
				(width 0.1)
				(type default)
			)
			(layer "B.Fab")
		)
		(fp_line
			(start 0.12065 0.3048)
			(end 0.67945 0.3048)
			(stroke
				(width 0.1)
				(type default)
			)
			(layer "B.Fab")
		)
		(fp_line
			(start 0.67945 -0.305054)
			(end 0.12065 -0.305054)
			(stroke
				(width 0.1)
				(type default)
			)
			(layer "B.Fab")
		)
		(fp_line
			(start 0.67945 0.3048)
			(end 0.67945 -0.305054)
			(stroke
				(width 0.1)
				(type default)
			)
			(layer "B.Fab")
		)
		(pad "1" smd circle
			(at 0.40005 0 180)
			(size 0 0)
			(layers "B.Cu" "B.Mask" "B.Paste")
			(net "P1V8_STBY_RC_VCC18A")
		)
		(pad "2" smd circle
			(at -0.40005 0 180)
			(size 0 0)
			(layers "B.Cu" "B.Mask" "B.Paste")
			(net "GND")
		)
	)
	(footprint ""
		(layer "B.Cu")
		(at 21.971 -24.003 -90)
		(property "Reference" "PC270"
			(at 0 0 90)
			(layer "B.SilkS")
			(hide yes)
			(effects
				(font
					(size 1.27 1.27)
				)
				(justify mirror)
			)
		)
		(property "Value" ""
			(at 0 0 90)
			(layer "B.Fab")
			(effects
				(font
					(size 1.27 1.27)
				)
				(justify mirror)
			)
		)
		(duplicate_pad_numbers_are_jumpers no)
		(fp_line
			(start -1.651 0.8382)
			(end 1.651 0.8382)
			(stroke
				(width 0.1524)
				(type default)
			)
			(layer "B.SilkS")
		)
		(fp_line
			(start 0 0.8382)
			(end 0 -0.8382)
			(stroke
				(width 0.1524)
				(type default)
			)
			(layer "B.SilkS")
		)
		(fp_line
			(start 1.651 0.8382)
			(end 1.651 -0.8382)
			(stroke
				(width 0.1524)
				(type default)
			)
			(layer "B.SilkS")
		)
		(fp_line
			(start -1.651 -0.8382)
			(end -1.651 0.8382)
			(stroke
				(width 0.1524)
				(type default)
			)
			(layer "B.SilkS")
		)
		(fp_line
			(start 1.651 -0.8382)
			(end -1.651 -0.8382)
			(stroke
				(width 0.1524)
				(type default)
			)
			(layer "B.SilkS")
		)
		(fp_line
			(start -1.55956 0.7366)
			(end -1.55956 -0.7366)
			(stroke
				(width 0.1)
				(type default)
			)
			(layer "B.Fab")
		)
		(fp_line
			(start -1.524 0.7366)
			(end -1.55956 0.7366)
			(stroke
				(width 0.1)
				(type default)
			)
			(layer "B.Fab")
		)
		(fp_line
			(start 1.524 0.7366)
			(end -1.524 0.7366)
			(stroke
				(width 0.1)
				(type default)
			)
			(layer "B.Fab")
		)
		(fp_line
			(start 1.55956 0.7366)
			(end 1.524 0.7366)
			(stroke
				(width 0.1)
				(type default)
			)
			(layer "B.Fab")
		)
		(fp_line
			(start -1.55956 -0.7366)
			(end -1.524 -0.7366)
			(stroke
				(width 0.1)
				(type default)
			)
			(layer "B.Fab")
		)
		(fp_line
			(start -1.524 -0.7366)
			(end 1.524 -0.7366)
			(stroke
				(width 0.1)
				(type default)
			)
			(layer "B.Fab")
		)
		(fp_line
			(start 1.524 -0.7366)
			(end 1.55956 -0.7366)
			(stroke
				(width 0.1)
				(type default)
			)
			(layer "B.Fab")
		)
		(fp_line
			(start 1.55956 -0.7366)
			(end 1.55956 0.7366)
			(stroke
				(width 0.1)
				(type default)
			)
			(layer "B.Fab")
		)
		(pad "1" smd rect
			(at 0.94996 0 270)
			(size 1.1176 1.3716)
			(layers "B.Cu" "B.Mask" "B.Paste")
			(net "P1V0_AUX")
		)
		(pad "2" smd rect
			(at -0.94996 0 270)
			(size 1.1176 1.3716)
			(layers "B.Cu" "B.Mask" "B.Paste")
			(net "GND")
		)
	)
	(footprint ""
		(layer "B.Cu")
		(at 39.93007 -46.119542 180)
		(property "Reference" "R149"
			(at 0 0 0)
			(layer "B.SilkS")
			(hide yes)
			(effects
				(font
					(size 1.27 1.27)
				)
				(justify mirror)
			)
		)
		(property "Value" ""
			(at 0 0 0)
			(layer "B.Fab")
			(effects
				(font
					(size 1.27 1.27)
				)
				(justify mirror)
			)
		)
		(duplicate_pad_numbers_are_jumpers no)
		(fp_line
			(start 0.7874 0.4064)
			(end 0.7874 -0.4064)
			(stroke
				(width 0.1524)
				(type default)
			)
			(layer "B.SilkS")
		)
		(fp_line
			(start 0.7874 -0.4064)
			(end -0.7874 -0.4064)
			(stroke
				(width 0.1524)
				(type default)
			)
			(layer "B.SilkS")
		)
		(fp_line
			(start -0.7874 0.4064)
			(end 0.7874 0.4064)
			(stroke
				(width 0.1524)
				(type default)
			)
			(layer "B.SilkS")
		)
		(fp_line
			(start -0.7874 -0.4064)
			(end -0.7874 0.4064)
			(stroke
				(width 0.1524)
				(type default)
			)
			(layer "B.SilkS")
		)
		(fp_line
			(start 0.67945 0.3048)
			(end 0.67945 -0.305054)
			(stroke
				(width 0.1)
				(type default)
			)
			(layer "B.Fab")
		)
		(fp_line
			(start 0.67945 -0.305054)
			(end 0.12065 -0.305054)
			(stroke
				(width 0.1)
				(type default)
			)
			(layer "B.Fab")
		)
		(fp_line
			(start 0.12065 0.3048)
			(end 0.67945 0.3048)
			(stroke
				(width 0.1)
				(type default)
			)
			(layer "B.Fab")
		)
		(fp_line
			(start 0.12065 0.2794)
			(end 0.12065 0.3048)
			(stroke
				(width 0.1)
				(type default)
			)
			(layer "B.Fab")
		)
		(fp_line
			(start 0.12065 -0.2794)
			(end -0.12065 -0.2794)
			(stroke
				(width 0.1)
				(type default)
			)
			(layer "B.Fab")
		)
		(fp_line
			(start 0.12065 -0.305054)
			(end 0.12065 -0.2794)
			(stroke
				(width 0.1)
				(type default)
			)
			(layer "B.Fab")
		)
		(fp_line
			(start -0.120396 0.3048)
			(end -0.120396 0.2794)
			(stroke
				(width 0.1)
				(type default)
			)
			(layer "B.Fab")
		)
		(fp_line
			(start -0.120396 0.2794)
			(end 0.12065 0.2794)
			(stroke
				(width 0.1)
				(type default)
			)
			(layer "B.Fab")
		)
		(fp_line
			(start -0.12065 -0.2794)
			(end -0.12065 -0.3048)
			(stroke
				(width 0.1)
				(type default)
			)
			(layer "B.Fab")
		)
		(fp_line
			(start -0.12065 -0.3048)
			(end -0.67945 -0.3048)
			(stroke
				(width 0.1)
				(type default)
			)
			(layer "B.Fab")
		)
		(fp_line
			(start -0.67945 0.3048)
			(end -0.120396 0.3048)
			(stroke
				(width 0.1)
				(type default)
			)
			(layer "B.Fab")
		)
		(fp_line
			(start -0.67945 -0.3048)
			(end -0.67945 0.3048)
			(stroke
				(width 0.1)
				(type default)
			)
			(layer "B.Fab")
		)
		(pad "1" smd circle
			(at 0.40005 0)
			(size 0 0)
			(layers "B.Cu" "B.Mask" "B.Paste")
			(net "P3V3_AUX")
		)
		(pad "2" smd circle
			(at -0.40005 0)
			(size 0 0)
			(layers "B.Cu" "B.Mask" "B.Paste")
			(net "SMB_BMC_MM12_SDA")
		)
	)
	(footprint ""
		(layer "B.Cu")
		(at 53.68798 -30.86608 -90)
		(property "Reference" "R260"
			(at 0 0 90)
			(layer "B.SilkS")
			(hide yes)
			(effects
				(font
					(size 1.27 1.27)
				)
				(justify mirror)
			)
		)
		(property "Value" ""
			(at 0 0 90)
			(layer "B.Fab")
			(effects
				(font
					(size 1.27 1.27)
				)
				(justify mirror)
			)
		)
		(duplicate_pad_numbers_are_jumpers no)
		(fp_line
			(start -0.7874 0.4064)
			(end 0.7874 0.4064)
			(stroke
				(width 0.1524)
				(type default)
			)
			(layer "B.SilkS")
		)
		(fp_line
			(start 0.7874 0.4064)
			(end 0.7874 -0.4064)
			(stroke
				(width 0.1524)
				(type default)
			)
			(layer "B.SilkS")
		)
		(fp_line
			(start -0.7874 -0.4064)
			(end -0.7874 0.4064)
			(stroke
				(width 0.1524)
				(type default)
			)
			(layer "B.SilkS")
		)
		(fp_line
			(start 0.7874 -0.4064)
			(end -0.7874 -0.4064)
			(stroke
				(width 0.1524)
				(type default)
			)
			(layer "B.SilkS")
		)
		(fp_line
			(start -0.67945 0.3048)
			(end -0.120396 0.3048)
			(stroke
				(width 0.1)
				(type default)
			)
			(layer "B.Fab")
		)
		(fp_line
			(start -0.120396 0.3048)
			(end -0.120396 0.2794)
			(stroke
				(width 0.1)
				(type default)
			)
			(layer "B.Fab")
		)
		(fp_line
			(start 0.12065 0.3048)
			(end 0.67945 0.3048)
			(stroke
				(width 0.1)
				(type default)
			)
			(layer "B.Fab")
		)
		(fp_line
			(start 0.67945 0.3048)
			(end 0.67945 -0.305054)
			(stroke
				(width 0.1)
				(type default)
			)
			(layer "B.Fab")
		)
		(fp_line
			(start -0.120396 0.2794)
			(end 0.12065 0.2794)
			(stroke
				(width 0.1)
				(type default)
			)
			(layer "B.Fab")
		)
		(fp_line
			(start 0.12065 0.2794)
			(end 0.12065 0.3048)
			(stroke
				(width 0.1)
				(type default)
			)
			(layer "B.Fab")
		)
		(fp_line
			(start -0.12065 -0.2794)
			(end -0.12065 -0.3048)
			(stroke
				(width 0.1)
				(type default)
			)
			(layer "B.Fab")
		)
		(fp_line
			(start 0.12065 -0.2794)
			(end -0.12065 -0.2794)
			(stroke
				(width 0.1)
				(type default)
			)
			(layer "B.Fab")
		)
		(fp_line
			(start -0.67945 -0.3048)
			(end -0.67945 0.3048)
			(stroke
				(width 0.1)
				(type default)
			)
			(layer "B.Fab")
		)
		(fp_line
			(start -0.12065 -0.3048)
			(end -0.67945 -0.3048)
			(stroke
				(width 0.1)
				(type default)
			)
			(layer "B.Fab")
		)
		(fp_line
			(start 0.12065 -0.305054)
			(end 0.12065 -0.2794)
			(stroke
				(width 0.1)
				(type default)
			)
			(layer "B.Fab")
		)
		(fp_line
			(start 0.67945 -0.305054)
			(end 0.12065 -0.305054)
			(stroke
				(width 0.1)
				(type default)
			)
			(layer "B.Fab")
		)
		(pad "1" smd circle
			(at 0.40005 0 90)
			(size 0 0)
			(layers "B.Cu" "B.Mask" "B.Paste")
			(net "P3V3_AUX")
		)
		(pad "2" smd circle
			(at -0.40005 0 90)
			(size 0 0)
			(layers "B.Cu" "B.Mask" "B.Paste")
			(net "SMB_BMC_MM9_SCL")
		)
	)
	(footprint ""
		(layer "B.Cu")
		(at 78.723744 -35.540188 -90)
		(property "Reference" "R334"
			(at 0 0 90)
			(layer "B.SilkS")
			(hide yes)
			(effects
				(font
					(size 1.27 1.27)
				)
				(justify mirror)
			)
		)
		(property "Value" ""
			(at 0 0 90)
			(layer "B.Fab")
			(effects
				(font
					(size 1.27 1.27)
				)
				(justify mirror)
			)
		)
		(duplicate_pad_numbers_are_jumpers no)
		(fp_line
			(start -0.7874 0.4064)
			(end 0.7874 0.4064)
			(stroke
				(width 0.1524)
				(type default)
			)
			(layer "B.SilkS")
		)
		(fp_line
			(start 0.7874 0.4064)
			(end 0.7874 -0.4064)
			(stroke
				(width 0.1524)
				(type default)
			)
			(layer "B.SilkS")
		)
		(fp_line
			(start -0.7874 -0.4064)
			(end -0.7874 0.4064)
			(stroke
				(width 0.1524)
				(type default)
			)
			(layer "B.SilkS")
		)
		(fp_line
			(start 0.7874 -0.4064)
			(end -0.7874 -0.4064)
			(stroke
				(width 0.1524)
				(type default)
			)
			(layer "B.SilkS")
		)
		(fp_line
			(start -0.67945 0.3048)
			(end -0.120396 0.3048)
			(stroke
				(width 0.1)
				(type default)
			)
			(layer "B.Fab")
		)
		(fp_line
			(start -0.120396 0.3048)
			(end -0.120396 0.2794)
			(stroke
				(width 0.1)
				(type default)
			)
			(layer "B.Fab")
		)
		(fp_line
			(start 0.12065 0.3048)
			(end 0.67945 0.3048)
			(stroke
				(width 0.1)
				(type default)
			)
			(layer "B.Fab")
		)
		(fp_line
			(start 0.67945 0.3048)
			(end 0.67945 -0.305054)
			(stroke
				(width 0.1)
				(type default)
			)
			(layer "B.Fab")
		)
		(fp_line
			(start -0.120396 0.2794)
			(end 0.12065 0.2794)
			(stroke
				(width 0.1)
				(type default)
			)
			(layer "B.Fab")
		)
		(fp_line
			(start 0.12065 0.2794)
			(end 0.12065 0.3048)
			(stroke
				(width 0.1)
				(type default)
			)
			(layer "B.Fab")
		)
		(fp_line
			(start -0.12065 -0.2794)
			(end -0.12065 -0.3048)
			(stroke
				(width 0.1)
				(type default)
			)
			(layer "B.Fab")
		)
		(fp_line
			(start 0.12065 -0.2794)
			(end -0.12065 -0.2794)
			(stroke
				(width 0.1)
				(type default)
			)
			(layer "B.Fab")
		)
		(fp_line
			(start -0.67945 -0.3048)
			(end -0.67945 0.3048)
			(stroke
				(width 0.1)
				(type default)
			)
			(layer "B.Fab")
		)
		(fp_line
			(start -0.12065 -0.3048)
			(end -0.67945 -0.3048)
			(stroke
				(width 0.1)
				(type default)
			)
			(layer "B.Fab")
		)
		(fp_line
			(start 0.12065 -0.305054)
			(end 0.12065 -0.2794)
			(stroke
				(width 0.1)
				(type default)
			)
			(layer "B.Fab")
		)
		(fp_line
			(start 0.67945 -0.305054)
			(end 0.12065 -0.305054)
			(stroke
				(width 0.1)
				(type default)
			)
			(layer "B.Fab")
		)
		(pad "1" smd circle
			(at 0.40005 0 90)
			(size 0 0)
			(layers "B.Cu" "B.Mask" "B.Paste")
			(net "GND")
		)
		(pad "2" smd circle
			(at -0.40005 0 90)
			(size 0 0)
			(layers "B.Cu" "B.Mask" "B.Paste")
			(net "M_BMC_DDR4_MA<8>")
		)
	)
)
